(kicad_pcb
	(version 20241229)
	(generator "pcbnew")
	(generator_version "9.0")
	(general
		(thickness 1.61)
		(legacy_teardrops no)
	)
	(paper "A3")
	(title_block
		(title "RDIMM DDR5 Tester")
		(date "2026-05-21")
		(rev "2.2.0")
		(company "Antmicro")
		(comment 9 "footprints 646-650 of 796")
	)
	(layers
		(0 "F.Cu" signal)
		(4 "In1.Cu" power)
		(6 "In2.Cu" mixed)
		(8 "In3.Cu" power)
		(10 "In4.Cu" mixed)
		(12 "In5.Cu" power)
		(14 "In6.Cu" mixed)
		(16 "In7.Cu" power)
		(18 "In8.Cu" power)
		(20 "In9.Cu" mixed)
		(22 "In10.Cu" power)
		(2 "B.Cu" signal)
		(9 "F.Adhes" user "F.Adhesive")
		(11 "B.Adhes" user "B.Adhesive")
		(13 "F.Paste" user)
		(15 "B.Paste" user)
		(5 "F.SilkS" user "F.Silkscreen")
		(7 "B.SilkS" user "B.Silkscreen")
		(1 "F.Mask" user)
		(3 "B.Mask" user)
		(17 "Dwgs.User" user "User.Drawings")
		(19 "Cmts.User" user "User.Comments")
		(21 "Eco1.User" user "User.Eco1")
		(23 "Eco2.User" user "User.Eco2")
		(25 "Edge.Cuts" user)
		(27 "Margin" user)
		(31 "F.CrtYd" user "F.Courtyard")
		(29 "B.CrtYd" user "B.Courtyard")
		(35 "F.Fab" user)
		(33 "B.Fab" user)
	)
	(footprint "antmicro-footprints:C_0402_1005Metric_EIA"
		(layer "B.Cu")
		(at 192.5 160)
		(descr "Capacitor SMD 0402 (1005 Metric), square (rectangular) end terminal, IPC_7351 nominal, (Body size source: IPC-SM-782 page 76, https://www.pcb-3d.com/wordpress/wp-content/uploads/ipc-sm-782a_amendment_1_and_2.pdf)")
		(tags "capacitor 0402")
		(property "Reference" "C97"
			(at -32.125 -9.775 0)
			(layer "B.SilkS")
			(effects
				(font
					(size 0.7 0.7)
					(thickness 0.15)
				)
				(justify right bottom mirror)
			)
		)
		(property "Value" "C_4u7_0402"
			(at 0 -1.169 0)
			(layer "B.Fab")
			(effects
				(font
					(size 0.7 0.7)
					(thickness 0.15)
				)
				(justify right bottom mirror)
			)
		)
		(property "Datasheet" "https://www.murata.com/products/productdetail?partno=GRM155R61A475MEAA%23"
			(at 0 0 0)
			(layer "F.Fab")
			(hide yes)
			(effects
				(font
					(size 1.27 1.27)
					(thickness 0.15)
				)
			)
		)
		(property "Manufacturer" "Murata"
			(at 0 0 0)
			(unlocked yes)
			(layer "B.Fab")
			(hide yes)
			(effects
				(font
					(size 1 1)
					(thickness 0.15)
				)
				(justify mirror)
			)
		)
		(property "MPN" "GRM155R61A475MEAAD"
			(at 0 0 0)
			(unlocked yes)
			(layer "B.Fab")
			(hide yes)
			(effects
				(font
					(size 1 1)
					(thickness 0.15)
				)
				(justify mirror)
			)
		)
		(property "Val" "4u7"
			(at 0 0 0)
			(unlocked yes)
			(layer "B.Fab")
			(hide yes)
			(effects
				(font
					(size 1 1)
					(thickness 0.15)
				)
				(justify mirror)
			)
		)
		(property "License" "Apache-2.0"
			(at 0 0 0)
			(unlocked yes)
			(layer "B.Fab")
			(hide yes)
			(effects
				(font
					(size 1 1)
					(thickness 0.15)
				)
				(justify mirror)
			)
		)
		(property "Author" "Antmicro"
			(at 0 0 0)
			(unlocked yes)
			(layer "B.Fab")
			(hide yes)
			(effects
				(font
					(size 1 1)
					(thickness 0.15)
				)
				(justify mirror)
			)
		)
		(property "Voltage" ""
			(at 0 0 0)
			(unlocked yes)
			(layer "B.Fab")
			(hide yes)
			(effects
				(font
					(size 1 1)
					(thickness 0.15)
				)
				(justify mirror)
			)
		)
		(property "Dielectric" ""
			(at 0 0 0)
			(unlocked yes)
			(layer "B.Fab")
			(hide yes)
			(effects
				(font
					(size 1 1)
					(thickness 0.15)
				)
				(justify mirror)
			)
		)
		(sheetname "/FPGA power/")
		(sheetfile "fpga-power.kicad_sch")
		(attr smd)
		(fp_rect
			(start -0.95 0.45)
			(end 0.95 -0.45)
			(stroke
				(width 0.05)
				(type default)
			)
			(fill no)
			(layer "B.CrtYd")
		)
		(fp_line
			(start -0.5 -0.248)
			(end -0.5 0.25)
			(stroke
				(width 0.15)
				(type solid)
			)
			(layer "B.Fab")
		)
		(fp_line
			(start -0.5 0.25)
			(end 0.498 0.25)
			(stroke
				(width 0.15)
				(type solid)
			)
			(layer "B.Fab")
		)
		(fp_line
			(start 0.498 -0.248)
			(end -0.5 -0.248)
			(stroke
				(width 0.15)
				(type solid)
			)
			(layer "B.Fab")
		)
		(fp_line
			(start 0.498 0.25)
			(end 0.498 -0.248)
			(stroke
				(width 0.15)
				(type solid)
			)
			(layer "B.Fab")
		)
		(fp_text user "Author: Antmicro"
			(at -0.9656 -5.569 180)
			(layer "B.Fab")
			(effects
				(font
					(size 0.7 0.7)
					(thickness 0.15)
				)
				(justify left bottom mirror)
			)
		)
		(fp_text user "${REFERENCE}"
			(at -0.9656 -3.169 180)
			(layer "B.Fab")
			(effects
				(font
					(size 0.7 0.7)
					(thickness 0.15)
				)
				(justify left bottom mirror)
			)
		)
		(fp_text user "License: Apache-2.0"
			(at -0.9656 -4.369 180)
			(layer "B.Fab")
			(effects
				(font
					(size 0.7 0.7)
					(thickness 0.15)
				)
				(justify left bottom mirror)
			)
		)
		(pad "1" smd roundrect
			(at -0.5 0 270)
			(size 0.6 0.6)
			(layers "B.Cu" "B.Mask" "B.Paste")
			(roundrect_rratio 0.25)
			(net 573 "+1V8_MGTVCCAUX")
			(pintype "passive")
		)
		(pad "2" smd roundrect
			(at 0.498 0)
			(size 0.6 0.6)
			(layers "B.Cu" "B.Mask" "B.Paste")
			(roundrect_rratio 0.25)
			(net 1 "GND")
			(pintype "passive")
		)
	)
	(footprint "antmicro-footprints:C_0402_1005Metric"
		(layer "B.Cu")
		(at 182.510001 167.45 90)
		(descr "Capacitor SMD 0402")
		(tags "capacitor SMD 0402")
		(property "Reference" "C292"
			(at -4 0.115999 90)
			(layer "B.SilkS")
			(effects
				(font
					(size 0.7 0.7)
					(thickness 0.15)
				)
				(justify right bottom mirror)
			)
		)
		(property "Value" "C_100n_0402"
			(at -1.022927 -2.155213 90)
			(layer "B.Fab")
			(effects
				(font
					(size 0.7 0.7)
					(thickness 0.15)
				)
				(justify right bottom mirror)
			)
		)
		(property "Datasheet" "https://www.murata.com/products/productdetail?partno=GRM155R61H104KE14%23"
			(at 0 0 90)
			(layer "F.Fab")
			(hide yes)
			(effects
				(font
					(size 1.27 1.27)
					(thickness 0.15)
				)
			)
		)
		(property "Manufacturer" "Murata"
			(at 0 0 90)
			(unlocked yes)
			(layer "B.Fab")
			(hide yes)
			(effects
				(font
					(size 1 1)
					(thickness 0.15)
				)
				(justify mirror)
			)
		)
		(property "MPN" "GRM155R61H104KE14D"
			(at 0 0 90)
			(unlocked yes)
			(layer "B.Fab")
			(hide yes)
			(effects
				(font
					(size 1 1)
					(thickness 0.15)
				)
				(justify mirror)
			)
		)
		(property "Val" "100n"
			(at 0 0 90)
			(unlocked yes)
			(layer "B.Fab")
			(hide yes)
			(effects
				(font
					(size 1 1)
					(thickness 0.15)
				)
				(justify mirror)
			)
		)
		(property "License" "Apache-2.0"
			(at 0 0 90)
			(unlocked yes)
			(layer "B.Fab")
			(hide yes)
			(effects
				(font
					(size 1 1)
					(thickness 0.15)
				)
				(justify mirror)
			)
		)
		(property "Author" "Antmicro"
			(at 0 0 90)
			(unlocked yes)
			(layer "B.Fab")
			(hide yes)
			(effects
				(font
					(size 1 1)
					(thickness 0.15)
				)
				(justify mirror)
			)
		)
		(property "Voltage" "50V"
			(at 0 0 90)
			(unlocked yes)
			(layer "B.Fab")
			(hide yes)
			(effects
				(font
					(size 1 1)
					(thickness 0.15)
				)
				(justify mirror)
			)
		)
		(property "Dielectric" "X5R"
			(at 0 0 90)
			(unlocked yes)
			(layer "B.Fab")
			(hide yes)
			(effects
				(font
					(size 1 1)
					(thickness 0.15)
				)
				(justify mirror)
			)
		)
		(sheetname "/FPGA MGT Interface/")
		(sheetfile "fpga-mgt.kicad_sch")
		(attr smd)
		(fp_rect
			(start -0.925 0.47)
			(end 0.925 -0.47)
			(stroke
				(width 0.05)
				(type default)
			)
			(fill no)
			(layer "B.CrtYd")
		)
		(fp_line
			(start 0.504 -0.248)
			(end -0.494 -0.248)
			(stroke
				(width 0.15)
				(type solid)
			)
			(layer "B.Fab")
		)
		(fp_line
			(start -0.494 -0.248)
			(end -0.494 0.25)
			(stroke
				(width 0.15)
				(type solid)
			)
			(layer "B.Fab")
		)
		(fp_line
			(start 0.504 0.25)
			(end 0.504 -0.248)
			(stroke
				(width 0.15)
				(type solid)
			)
			(layer "B.Fab")
		)
		(fp_line
			(start -0.494 0.25)
			(end 0.504 0.25)
			(stroke
				(width 0.15)
				(type solid)
			)
			(layer "B.Fab")
		)
		(fp_text user "Author: Antmicro"
			(at -0.939 -3.399 270)
			(layer "B.Fab")
			(effects
				(font
					(size 0.7 0.7)
					(thickness 0.15)
				)
				(justify left bottom mirror)
			)
		)
		(fp_text user "License: Apache-2.0"
			(at -0.939 -5.799 270)
			(layer "B.Fab")
			(effects
				(font
					(size 0.7 0.7)
					(thickness 0.15)
				)
				(justify left bottom mirror)
			)
		)
		(fp_text user "${REFERENCE}"
			(at -0.939 -4.599 270)
			(layer "B.Fab")
			(effects
				(font
					(size 0.7 0.7)
					(thickness 0.15)
				)
				(justify left bottom mirror)
			)
		)
		(pad "1" smd roundrect
			(at -0.48 0 90)
			(size 0.59 0.64)
			(layers "B.Cu" "B.Mask" "B.Paste")
			(roundrect_rratio 0.25)
			(net 294 "/FPGA MGT Interface/HDMI_OUT.D2_P")
			(pintype "passive")
		)
		(pad "2" smd roundrect
			(at 0.48 0 90)
			(size 0.59 0.64)
			(layers "B.Cu" "B.Mask" "B.Paste")
			(roundrect_rratio 0.25)
			(net 628 "/FPGA MGT Interface/HDMI_FPGA.TX2_P")
			(pintype "passive")
		)
	)
	(footprint "antmicro-footprints:R_0402_1005Metric"
		(layer "B.Cu")
		(at 253.75 117.11 180)
		(descr "Resistor SMD 0402")
		(tags "resistor SMD 0402")
		(property "Reference" "R244"
			(at -1.37 0.57 0)
			(layer "B.SilkS")
			(effects
				(font
					(size 0.7 0.7)
					(thickness 0.15)
				)
				(justify left bottom mirror)
			)
		)
		(property "Value" "R_47k_0402"
			(at -1.011843 -1.772047 0)
			(layer "B.Fab")
			(effects
				(font
					(size 0.7 0.7)
					(thickness 0.15)
				)
				(justify left bottom mirror)
			)
		)
		(property "Datasheet" "https://www.bourns.com/docs/product-datasheets/cr.pdf"
			(at 0 0 180)
			(layer "F.Fab")
			(hide yes)
			(effects
				(font
					(size 1.27 1.27)
					(thickness 0.15)
				)
			)
		)
		(property "MPN" "CR0402-FX-4702GLF"
			(at 0 0 180)
			(unlocked yes)
			(layer "B.Fab")
			(hide yes)
			(effects
				(font
					(size 1 1)
					(thickness 0.15)
				)
				(justify mirror)
			)
		)
		(property "Manufacturer" "Bourns"
			(at 0 0 180)
			(unlocked yes)
			(layer "B.Fab")
			(hide yes)
			(effects
				(font
					(size 1 1)
					(thickness 0.15)
				)
				(justify mirror)
			)
		)
		(property "License" "Apache-2.0"
			(at 0 0 180)
			(unlocked yes)
			(layer "B.Fab")
			(hide yes)
			(effects
				(font
					(size 1 1)
					(thickness 0.15)
				)
				(justify mirror)
			)
		)
		(property "Author" "Antmicro"
			(at 0 0 180)
			(unlocked yes)
			(layer "B.Fab")
			(hide yes)
			(effects
				(font
					(size 1 1)
					(thickness 0.15)
				)
				(justify mirror)
			)
		)
		(property "Val" "47k"
			(at 0 0 180)
			(unlocked yes)
			(layer "B.Fab")
			(hide yes)
			(effects
				(font
					(size 1 1)
					(thickness 0.15)
				)
				(justify mirror)
			)
		)
		(property "Tolerance" "1%"
			(at 0 0 180)
			(unlocked yes)
			(layer "B.Fab")
			(hide yes)
			(effects
				(font
					(size 1 1)
					(thickness 0.15)
				)
				(justify mirror)
			)
		)
		(sheetname "/DDR5 RDIMM/")
		(sheetfile "ddr5-rdimm.kicad_sch")
		(attr smd)
		(fp_rect
			(start -0.925 0.47)
			(end 0.925 -0.47)
			(stroke
				(width 0.05)
				(type default)
			)
			(fill no)
			(layer "B.CrtYd")
		)
		(fp_rect
			(start -0.5 0.25)
			(end 0.5 -0.25)
			(stroke
				(width 0.15)
				(type solid)
			)
			(fill no)
			(layer "B.Fab")
		)
		(fp_text user "Author: Antmicro"
			(at -0.95 -4.169 0)
			(layer "B.Fab")
			(effects
				(font
					(size 0.7 0.7)
					(thickness 0.15)
				)
				(justify left bottom mirror)
			)
		)
		(fp_text user "${REFERENCE}"
			(at -0.95 -3.168 0)
			(layer "B.Fab")
			(effects
				(font
					(size 0.7 0.7)
					(thickness 0.15)
				)
				(justify left bottom mirror)
			)
		)
		(fp_text user "License: Apache-2.0"
			(at -0.95 -5.169 0)
			(layer "B.Fab")
			(effects
				(font
					(size 0.7 0.7)
					(thickness 0.15)
				)
				(justify left bottom mirror)
			)
		)
		(pad "1" smd roundrect
			(at -0.48 0 180)
			(size 0.59 0.64)
			(layers "B.Cu" "B.Mask" "B.Paste")
			(roundrect_rratio 0.25)
			(net 807 "Net-(Q26-D)")
			(pintype "passive")
		)
		(pad "2" smd roundrect
			(at 0.48 0 180)
			(size 0.59 0.64)
			(layers "B.Cu" "B.Mask" "B.Paste")
			(roundrect_rratio 0.25)
			(net 151 "+3V3")
			(pintype "passive")
		)
	)
	(footprint "antmicro-footprints:C_0402_1005Metric"
		(layer "B.Cu")
		(at 247.475 187.338)
		(descr "Capacitor SMD 0402")
		(tags "capacitor SMD 0402")
		(property "Reference" "C318"
			(at 0.825 0.461 0)
			(layer "B.SilkS")
			(effects
				(font
					(size 0.7 0.7)
					(thickness 0.15)
				)
				(justify right bottom mirror)
			)
		)
		(property "Value" "C_100n_0402"
			(at -1.022927 -2.155213 0)
			(layer "B.Fab")
			(effects
				(font
					(size 0.7 0.7)
					(thickness 0.15)
				)
				(justify right bottom mirror)
			)
		)
		(property "Datasheet" "https://www.murata.com/products/productdetail?partno=GRM155R61H104KE14%23"
			(at 0 0 0)
			(layer "F.Fab")
			(hide yes)
			(effects
				(font
					(size 1.27 1.27)
					(thickness 0.15)
				)
			)
		)
		(property "MPN" "GRM155R61H104KE14D"
			(at 0 0 0)
			(unlocked yes)
			(layer "B.Fab")
			(hide yes)
			(effects
				(font
					(size 1 1)
					(thickness 0.15)
				)
				(justify mirror)
			)
		)
		(property "Manufacturer" "Murata"
			(at 0 0 0)
			(unlocked yes)
			(layer "B.Fab")
			(hide yes)
			(effects
				(font
					(size 1 1)
					(thickness 0.15)
				)
				(justify mirror)
			)
		)
		(property "License" "Apache-2.0"
			(at 0 0 0)
			(unlocked yes)
			(layer "B.Fab")
			(hide yes)
			(effects
				(font
					(size 1 1)
					(thickness 0.15)
				)
				(justify mirror)
			)
		)
		(property "Author" "Antmicro"
			(at 0 0 0)
			(unlocked yes)
			(layer "B.Fab")
			(hide yes)
			(effects
				(font
					(size 1 1)
					(thickness 0.15)
				)
				(justify mirror)
			)
		)
		(property "Val" "100n"
			(at 0 0 0)
			(unlocked yes)
			(layer "B.Fab")
			(hide yes)
			(effects
				(font
					(size 1 1)
					(thickness 0.15)
				)
				(justify mirror)
			)
		)
		(property "Voltage" "50V"
			(at 0 0 0)
			(unlocked yes)
			(layer "B.Fab")
			(hide yes)
			(effects
				(font
					(size 1 1)
					(thickness 0.15)
				)
				(justify mirror)
			)
		)
		(property "Dielectric" "X5R"
			(at 0 0 0)
			(unlocked yes)
			(layer "B.Fab")
			(hide yes)
			(effects
				(font
					(size 1 1)
					(thickness 0.15)
				)
				(justify mirror)
			)
		)
		(sheetname "/I^{2}C + I3C/")
		(sheetfile "i2c.kicad_sch")
		(attr smd)
		(fp_rect
			(start -0.925 0.47)
			(end 0.925 -0.47)
			(stroke
				(width 0.05)
				(type default)
			)
			(fill no)
			(layer "B.CrtYd")
		)
		(fp_line
			(start -0.494 -0.248)
			(end -0.494 0.25)
			(stroke
				(width 0.15)
				(type solid)
			)
			(layer "B.Fab")
		)
		(fp_line
			(start -0.494 0.25)
			(end 0.504 0.25)
			(stroke
				(width 0.15)
				(type solid)
			)
			(layer "B.Fab")
		)
		(fp_line
			(start 0.504 -0.248)
			(end -0.494 -0.248)
			(stroke
				(width 0.15)
				(type solid)
			)
			(layer "B.Fab")
		)
		(fp_line
			(start 0.504 0.25)
			(end 0.504 -0.248)
			(stroke
				(width 0.15)
				(type solid)
			)
			(layer "B.Fab")
		)
		(fp_text user "Author: Antmicro"
			(at -0.939 -3.399 180)
			(layer "B.Fab")
			(effects
				(font
					(size 0.7 0.7)
					(thickness 0.15)
				)
				(justify left bottom mirror)
			)
		)
		(fp_text user "${REFERENCE}"
			(at -0.939 -4.599 180)
			(layer "B.Fab")
			(effects
				(font
					(size 0.7 0.7)
					(thickness 0.15)
				)
				(justify left bottom mirror)
			)
		)
		(fp_text user "License: Apache-2.0"
			(at -0.939 -5.799 180)
			(layer "B.Fab")
			(effects
				(font
					(size 0.7 0.7)
					(thickness 0.15)
				)
				(justify left bottom mirror)
			)
		)
		(pad "1" smd roundrect
			(at -0.48 0)
			(size 0.59 0.64)
			(layers "B.Cu" "B.Mask" "B.Paste")
			(roundrect_rratio 0.25)
			(net 1 "GND")
			(pintype "passive")
		)
		(pad "2" smd roundrect
			(at 0.48 0)
			(size 0.59 0.64)
			(layers "B.Cu" "B.Mask" "B.Paste")
			(roundrect_rratio 0.25)
			(net 662 "Net-(Q22-D)")
			(pintype "passive")
		)
	)
	(footprint "antmicro-footprints:R_0402_1005Metric_EIA"
		(layer "B.Cu")
		(at 199 157.5 -90)
		(descr "Resistor SMD 0402 (1005 Metric), square (rectangular) end terminal, IPC_7351 nominal, (Body size source: IPC-SM-782 page 76, https://www.pcb-3d.com/wordpress/wp-content/uploads/ipc-sm-782a_amendment_1_and_2.pdf)")
		(tags "resistor 0402")
		(property "Reference" "R36"
			(at -11.925 29.575 90)
			(layer "B.SilkS")
			(effects
				(font
					(size 0.7 0.7)
					(thickness 0.15)
				)
				(justify left bottom mirror)
			)
		)
		(property "Value" "R_100R_0402"
			(at 0 -1.169 90)
			(layer "B.Fab")
			(effects
				(font
					(size 0.7 0.7)
					(thickness 0.15)
				)
				(justify left bottom mirror)
			)
		)
		(property "Datasheet" "https://www.bourns.com/docs/product-datasheets/cr.pdf"
			(at 0 0 270)
			(layer "F.Fab")
			(hide yes)
			(effects
				(font
					(size 1.27 1.27)
					(thickness 0.15)
				)
			)
		)
		(property "Manufacturer" "Bourns"
			(at 0 0 270)
			(unlocked yes)
			(layer "B.Fab")
			(hide yes)
			(effects
				(font
					(size 1 1)
					(thickness 0.15)
				)
				(justify mirror)
			)
		)
		(property "MPN" "CR0402-FX-1000GLF"
			(at 0 0 270)
			(unlocked yes)
			(layer "B.Fab")
			(hide yes)
			(effects
				(font
					(size 1 1)
					(thickness 0.15)
				)
				(justify mirror)
			)
		)
		(property "Val" "100R"
			(at 0 0 270)
			(unlocked yes)
			(layer "B.Fab")
			(hide yes)
			(effects
				(font
					(size 1 1)
					(thickness 0.15)
				)
				(justify mirror)
			)
		)
		(property "License" "Apache-2.0"
			(at 0 0 270)
			(unlocked yes)
			(layer "B.Fab")
			(hide yes)
			(effects
				(font
					(size 1 1)
					(thickness 0.15)
				)
				(justify mirror)
			)
		)
		(property "Author" "Antmicro"
			(at 0 0 270)
			(unlocked yes)
			(layer "B.Fab")
			(hide yes)
			(effects
				(font
					(size 1 1)
					(thickness 0.15)
				)
				(justify mirror)
			)
		)
		(property "Tolerance" "1%"
			(at 0 0 270)
			(unlocked yes)
			(layer "B.Fab")
			(hide yes)
			(effects
				(font
					(size 1 1)
					(thickness 0.15)
				)
				(justify mirror)
			)
		)
		(sheetname "/FPGA power/")
		(sheetfile "fpga-power.kicad_sch")
		(attr smd)
		(fp_rect
			(start -0.95 0.45)
			(end 0.95 -0.45)
			(stroke
				(width 0.05)
				(type default)
			)
			(fill no)
			(layer "B.CrtYd")
		)
		(fp_line
			(start -0.5 0.25)
			(end 0.499 0.25)
			(stroke
				(width 0.15)
				(type solid)
			)
			(layer "B.Fab")
		)
		(fp_line
			(start 0.499 0.25)
			(end 0.499 -0.249)
			(stroke
				(width 0.15)
				(type solid)
			)
			(layer "B.Fab")
		)
		(fp_line
			(start -0.5 -0.249)
			(end -0.5 0.25)
			(stroke
				(width 0.15)
				(type solid)
			)
			(layer "B.Fab")
		)
		(fp_line
			(start 0.499 -0.249)
			(end -0.5 -0.249)
			(stroke
				(width 0.15)
				(type solid)
			)
			(layer "B.Fab")
		)
		(fp_text user "${REFERENCE}"
			(at -0.95 -3.169 90)
			(layer "B.Fab")
			(effects
				(font
					(size 0.7 0.7)
					(thickness 0.15)
				)
				(justify left bottom mirror)
			)
		)
		(fp_text user "Author: Antmicro"
			(at -0.95 -5.569 90)
			(layer "B.Fab")
			(effects
				(font
					(size 0.7 0.7)
					(thickness 0.15)
				)
				(justify left bottom mirror)
			)
		)
		(fp_text user "License: Apache-2.0"
			(at -0.95 -4.369 90)
			(layer "B.Fab")
			(effects
				(font
					(size 0.7 0.7)
					(thickness 0.15)
				)
				(justify left bottom mirror)
			)
		)
		(pad "1" smd roundrect
			(at -0.5 0 180)
			(size 0.6 0.6)
			(layers "B.Cu" "B.Mask" "B.Paste")
			(roundrect_rratio 0.25)
			(net 288 "Net-(U34L-MGTRREF_R)")
			(pintype "passive")
		)
		(pad "2" smd roundrect
			(at 0.499 0 270)
			(size 0.6 0.6)
			(layers "B.Cu" "B.Mask" "B.Paste")
			(roundrect_rratio 0.25)
			(net 172 "+1V2_MGTAVTT")
			(pintype "passive")
		)
	)
)
